# BASEBOARD_FAB2 (Tioga Pass) — schematic netlist excerpt (pin names and nets, part order shuffled) for the footprints in the layout excerpt that follows; sources: Cadence DE-HDL packaged netlist, KiCad conversion of Wiwynn_Tioga_Pass_MB.brd

C2D37  CAP_A  22.0UF 4V 20% X6S  pkg 0603V  page 76 : A = PVCCIN_CPU1 ; B = GND
R4D46  RES  22.1 1.0% CHIP  pkg 0402  page 213 : A = PWRGD_PVCCIO_CPU1_R ; B = PWRGD_PVCCIO_CPU1
C9F1  SC22U16V5MX-4-GP  20%  pkg SMD-BCG5  page 240 : \1\ = VR_FET_SW_P12V_STBY_P3V3_STBY ; \2\ = GND

(kicad_pcb
	(version 20260206)
	(generator "pcbnew")
	(generator_version "10.0")
	(general
		(thickness 1.6)
		(legacy_teardrops no)
	)
	(paper "A4")
	(title_block
		(title "Wiwynn_Tioga_Pass_MB.brd")
		(comment 1 "Tioga Pass / footprints 398-400 of 4770")
	)
	(layers
		(0 "F.Cu" signal "TOP")
		(4 "In1.Cu" signal "L2GND")
		(6 "In2.Cu" signal "L3")
		(8 "In3.Cu" signal "L4GND")
		(10 "In4.Cu" signal "L5")
		(12 "In5.Cu" signal "L6GND")
		(14 "In6.Cu" signal "L7VCC")
		(16 "In7.Cu" signal "L8VCC")
		(18 "In8.Cu" signal "L9GND")
		(20 "In9.Cu" signal "L10")
		(22 "In10.Cu" signal "L11GND")
		(24 "In11.Cu" signal "L12")
		(26 "In12.Cu" signal "L13GND")
		(2 "B.Cu" signal "BOTTOM")
		(9 "F.Adhes" user "F.Adhesive")
		(11 "B.Adhes" user "B.Adhesive")
		(13 "F.Paste" user "Package Geometry/Pastemask Top")
		(15 "B.Paste" user "Package Geometry/Pastemask Bottom")
		(5 "F.SilkS" user "Ref Des/Silkscreen Top")
		(7 "B.SilkS" user "Ref Des/Silkscreen Bottom")
		(1 "F.Mask" user "Board Geometry/Soldermask Top")
		(3 "B.Mask" user "Board Geometry/Soldermask Bottom")
		(17 "Dwgs.User" user "User.Drawings")
		(19 "Cmts.User" user "User.Comments")
		(21 "Eco1.User" user "User.Eco1")
		(23 "Eco2.User" user "User.Eco2")
		(25 "Edge.Cuts" user "Board Geometry/Outline")
		(27 "Margin" user)
		(31 "F.CrtYd" user "Package Geometry/Place Bound Top")
		(29 "B.CrtYd" user "Package Geometry/Place Bound Bottom")
		(35 "F.Fab" user "Ref Des/Assembly Top")
		(33 "B.Fab" user "Ref Des/Assembly Bottom")
	)
	(footprint ""
		(layer "F.Cu")
		(at 166.37 -70.6374 180)
		(property "Reference" "R4D46"
			(at 0 0 180)
			(layer "F.SilkS")
			(hide yes)
			(effects
				(font
					(size 1.27 1.27)
				)
			)
		)
		(property "Value" ""
			(at 0 0 180)
			(layer "F.Fab")
			(effects
				(font
					(size 1.27 1.27)
				)
			)
		)
		(duplicate_pad_numbers_are_jumpers no)
		(fp_poly
			(pts
				(xy -0.2794 -0.1016) (xy 0.2794 -0.1016) (xy 0.2794 0.9906) (xy -0.2794 0.9906)
			)
			(stroke
				(width 0)
				(type default)
			)
			(fill no)
			(layer "F.CrtYd")
		)
		(fp_line
			(start 0.2794 0.9906)
			(end 0.2794 -0.1016)
			(stroke
				(width 0.1)
				(type default)
			)
			(layer "F.Fab")
		)
		(fp_line
			(start 0.2794 -0.1016)
			(end -0.2794 -0.1016)
			(stroke
				(width 0.1)
				(type default)
			)
			(layer "F.Fab")
		)
		(fp_line
			(start -0.2794 0.9906)
			(end 0.2794 0.9906)
			(stroke
				(width 0.1)
				(type default)
			)
			(layer "F.Fab")
		)
		(fp_line
			(start -0.2794 -0.1016)
			(end -0.2794 0.9906)
			(stroke
				(width 0.1)
				(type default)
			)
			(layer "F.Fab")
		)
		(pad "1" smd rect
			(at 0 0 180)
			(size 0.508 0.508)
			(layers "F.Cu" "F.Mask" "F.Paste")
			(net "PWRGD_PVCCIO_CPU1_R")
		)
		(pad "2" smd rect
			(at 0 0.889 180)
			(size 0.508 0.508)
			(layers "F.Cu" "F.Mask" "F.Paste")
			(net "PWRGD_PVCCIO_CPU1")
		)
		(zone
			(layer "F.Cu")
			(hatch none 0.5)
			(connect_pads
				(clearance 0)
			)
			(min_thickness 0.25)
			(keepout
				(tracks not_allowed)
				(vias allowed)
				(pads allowed)
				(copperpour not_allowed)
				(footprints allowed)
			)
			(placement
				(enabled no)
				(sheetname "")
			)
			(fill
				(thermal_gap 0.5)
				(thermal_bridge_width 0.5)
				(island_removal_mode 0)
			)
			(polygon
				(pts
					(xy 166.624 -71.2724) (xy 166.116 -71.2724) (xy 166.116 -70.8914) (xy 166.624 -70.8914)
				)
			)
		)
		(zone
			(layer "F.Cu")
			(hatch none 0.5)
			(connect_pads
				(clearance 0)
			)
			(min_thickness 0.25)
			(keepout
				(tracks allowed)
				(vias not_allowed)
				(pads allowed)
				(copperpour not_allowed)
				(footprints allowed)
			)
			(placement
				(enabled no)
				(sheetname "")
			)
			(fill
				(thermal_gap 0.5)
				(thermal_bridge_width 0.5)
				(island_removal_mode 0)
			)
			(polygon
				(pts
					(xy 166.624 -70.8914) (xy 166.116 -70.8914) (xy 166.116 -71.2724) (xy 166.624 -71.2724)
				)
			)
		)
	)
	(footprint ""
		(layer "F.Cu")
		(at 101.92004 -73.318116)
		(property "Reference" "C2D37"
			(at 0 0 0)
			(layer "F.SilkS")
			(hide yes)
			(effects
				(font
					(size 1.27 1.27)
				)
			)
		)
		(property "Value" ""
			(at 0 0 0)
			(layer "F.Fab")
			(effects
				(font
					(size 1.27 1.27)
				)
			)
		)
		(duplicate_pad_numbers_are_jumpers no)
		(fp_poly
			(pts
				(xy -0.4953 -0.2032) (xy 0.4953 -0.2032) (xy 0.4953 1.6002) (xy -0.4953 1.6002)
			)
			(stroke
				(width 0)
				(type default)
			)
			(fill no)
			(layer "F.CrtYd")
		)
		(fp_line
			(start -0.4953 -0.2032)
			(end 0.4953 -0.2032)
			(stroke
				(width 0.1)
				(type default)
			)
			(layer "F.Fab")
		)
		(fp_line
			(start -0.4953 1.6002)
			(end -0.4953 -0.2032)
			(stroke
				(width 0.1)
				(type default)
			)
			(layer "F.Fab")
		)
		(fp_line
			(start 0.4953 -0.2032)
			(end 0.4953 1.6002)
			(stroke
				(width 0.1)
				(type default)
			)
			(layer "F.Fab")
		)
		(fp_line
			(start 0.4953 1.6002)
			(end -0.4953 1.6002)
			(stroke
				(width 0.1)
				(type default)
			)
			(layer "F.Fab")
		)
		(pad "1" smd rect
			(at 0 0)
			(size 0.762 0.889)
			(layers "F.Cu" "F.Mask" "F.Paste")
			(net "PVCCIN_CPU1")
		)
		(pad "2" smd rect
			(at 0 1.397)
			(size 0.762 0.889)
			(layers "F.Cu" "F.Mask" "F.Paste")
			(net "GND")
		)
		(zone
			(layer "F.Cu")
			(hatch none 0.5)
			(connect_pads
				(clearance 0)
			)
			(min_thickness 0.25)
			(keepout
				(tracks not_allowed)
				(vias allowed)
				(pads allowed)
				(copperpour not_allowed)
				(footprints allowed)
			)
			(placement
				(enabled no)
				(sheetname "")
			)
			(fill
				(thermal_gap 0.5)
				(thermal_bridge_width 0.5)
				(island_removal_mode 0)
			)
			(polygon
				(pts
					(xy 101.53904 -72.873616) (xy 102.30104 -72.873616) (xy 102.30104 -72.365616) (xy 101.53904 -72.365616)
				)
			)
		)
	)
	(footprint ""
		(layer "F.Cu")
		(at 476.031814 -22.405848)
		(property "Reference" "C9F1"
			(at 0 0 0)
			(layer "F.SilkS")
			(hide yes)
			(effects
				(font
					(size 1.27 1.27)
				)
			)
		)
		(property "Value" "*"
			(at -0.0762 -6.2357 0)
			(unlocked yes)
			(layer "F.Fab")
			(hide yes)
			(effects
				(font
					(size 1.27 1.016)
					(thickness 0.1524)
				)
			)
		)
		(property "Device Type" "SC22U16V5MX-4-GP_SMD-BCG5-SC22A"
			(at -0.0762 -8.2677 0)
			(unlocked yes)
			(layer "F.Fab")
			(hide yes)
			(effects
				(font
					(size 1.27 1.016)
					(thickness 0.1524)
				)
			)
		)
		(duplicate_pad_numbers_are_jumpers no)
		(fp_line
			(start 0.635 0)
			(end -0.635 0)
			(stroke
				(width 0.508)
				(type default)
			)
			(layer "F.SilkS")
		)
		(fp_rect
			(start -0.9652 1.778)
			(end 0.9652 -1.778)
			(stroke
				(width 0)
				(type default)
			)
			(fill no)
			(layer "F.CrtYd")
		)
		(fp_poly
			(pts
				(xy -0.9652 -1.778) (xy 0.9652 -1.778) (xy 0.9652 1.778) (xy -0.9652 1.778)
			)
			(stroke
				(width 0)
				(type default)
			)
			(fill no)
			(layer "F.Fab")
		)
		(pad "1" smd rect
			(at 0 -0.9652)
			(size 1.397 1.143)
			(layers "F.Cu" "F.Mask" "F.Paste")
			(net "VR_FET_SW_P12V_STBY_P3V3_STBY")
		)
		(pad "2" smd rect
			(at 0 0.9652)
			(size 1.397 1.143)
			(layers "F.Cu" "F.Mask" "F.Paste")
			(net "GND")
		)
	)
)
